# S9S_MB_2U (Grand Teton) — schematic netlist excerpt (pin names and nets, part order shuffled) for the footprints in the layout excerpt that follows; sources: Cadence DE-HDL packaged netlist, KiCad conversion of 03242023_DA0F0TMBIJ0_F0T_Motherboard_J_brd_V01_OCP.brd

C3274  Q_CAP  1000PF 50V 5% X7R  pkg 0402  page 274 : A = PVCCINFAON_CPU0_EN_R ; B = GND
R4729  Q_RES  0 5% CHIP  pkg 0402LF  page 227 : A = GPU_PRSNT_N_ISO ; B = GPU_PRSNT_N_ISO_R1

(kicad_pcb
	(version 20260206)
	(generator "pcbnew")
	(generator_version "10.0")
	(general
		(thickness 1.6)
		(legacy_teardrops no)
	)
	(paper "A4")
	(title_block
		(title "03242023_DA0F0TMBIJ0_F0T_Motherboard_J_brd_V01_OCP.brd")
		(comment 1 "Grand Teton / footprints 2488-2489 of 6105")
	)
	(layers
		(0 "F.Cu" signal "TOP")
		(4 "In1.Cu" signal "GND")
		(6 "In2.Cu" signal "IN1")
		(8 "In3.Cu" signal "GND1")
		(10 "In4.Cu" signal "IN2")
		(12 "In5.Cu" signal "GND2")
		(14 "In6.Cu" signal "IN3")
		(16 "In7.Cu" signal "GND3")
		(18 "In8.Cu" signal "VCC")
		(20 "In9.Cu" signal "VCC1")
		(22 "In10.Cu" signal "GND4")
		(24 "In11.Cu" signal "IN4")
		(26 "In12.Cu" signal "GND5")
		(28 "In13.Cu" signal "IN5")
		(30 "In14.Cu" signal "GND6")
		(32 "In15.Cu" signal "IN6")
		(34 "In16.Cu" signal "GND7")
		(2 "B.Cu" signal "BOTTOM")
		(9 "F.Adhes" user "F.Adhesive")
		(11 "B.Adhes" user "B.Adhesive")
		(13 "F.Paste" user "Package Geometry/Pastemask Top")
		(15 "B.Paste" user "Package Geometry/Pastemask Bottom")
		(5 "F.SilkS" user "Ref Des/Silkscreen Top")
		(7 "B.SilkS" user "Ref Des/Silkscreen Bottom")
		(1 "F.Mask" user "Board Geometry/Soldermask Top")
		(3 "B.Mask" user "Board Geometry/Soldermask Bottom")
		(17 "Dwgs.User" user "User.Drawings")
		(19 "Cmts.User" user "User.Comments")
		(21 "Eco1.User" user "User.Eco1")
		(23 "Eco2.User" user "User.Eco2")
		(25 "Edge.Cuts" user "Board Geometry/Outline")
		(27 "Margin" user)
		(31 "F.CrtYd" user "Package Geometry/Place Bound Top")
		(29 "B.CrtYd" user "Package Geometry/Place Bound Bottom")
		(35 "F.Fab" user "Ref Des/Assembly Top")
		(33 "B.Fab" user "Ref Des/Assembly Bottom")
	)
	(footprint ""
		(layer "F.Cu")
		(at 430.600104 -134.494778)
		(property "Reference" "C3274"
			(at 0 0 0)
			(layer "F.SilkS")
			(hide yes)
			(effects
				(font
					(size 1.27 1.27)
				)
			)
		)
		(property "Value" ""
			(at 0 0 0)
			(layer "F.Fab")
			(effects
				(font
					(size 1.27 1.27)
				)
			)
		)
		(duplicate_pad_numbers_are_jumpers no)
		(fp_line
			(start -0.7874 -0.4064)
			(end 0.7874 -0.4064)
			(stroke
				(width 0.1524)
				(type default)
			)
			(layer "F.SilkS")
		)
		(fp_line
			(start -0.7874 0.4064)
			(end -0.7874 -0.4064)
			(stroke
				(width 0.1524)
				(type default)
			)
			(layer "F.SilkS")
		)
		(fp_line
			(start 0.7874 -0.4064)
			(end 0.7874 0.4064)
			(stroke
				(width 0.1524)
				(type default)
			)
			(layer "F.SilkS")
		)
		(fp_line
			(start 0.7874 0.4064)
			(end -0.7874 0.4064)
			(stroke
				(width 0.1524)
				(type default)
			)
			(layer "F.SilkS")
		)
		(fp_line
			(start -0.67945 -0.305054)
			(end -0.12065 -0.305054)
			(stroke
				(width 0.1)
				(type default)
			)
			(layer "F.Fab")
		)
		(fp_line
			(start -0.67945 0.3048)
			(end -0.67945 -0.305054)
			(stroke
				(width 0.1)
				(type default)
			)
			(layer "F.Fab")
		)
		(fp_line
			(start -0.12065 -0.305054)
			(end -0.12065 -0.2794)
			(stroke
				(width 0.1)
				(type default)
			)
			(layer "F.Fab")
		)
		(fp_line
			(start -0.12065 -0.2794)
			(end 0.12065 -0.2794)
			(stroke
				(width 0.1)
				(type default)
			)
			(layer "F.Fab")
		)
		(fp_line
			(start -0.12065 0.2794)
			(end -0.12065 0.3048)
			(stroke
				(width 0.1)
				(type default)
			)
			(layer "F.Fab")
		)
		(fp_line
			(start -0.12065 0.3048)
			(end -0.67945 0.3048)
			(stroke
				(width 0.1)
				(type default)
			)
			(layer "F.Fab")
		)
		(fp_line
			(start 0.120396 0.2794)
			(end -0.12065 0.2794)
			(stroke
				(width 0.1)
				(type default)
			)
			(layer "F.Fab")
		)
		(fp_line
			(start 0.120396 0.3048)
			(end 0.120396 0.2794)
			(stroke
				(width 0.1)
				(type default)
			)
			(layer "F.Fab")
		)
		(fp_line
			(start 0.12065 -0.3048)
			(end 0.67945 -0.3048)
			(stroke
				(width 0.1)
				(type default)
			)
			(layer "F.Fab")
		)
		(fp_line
			(start 0.12065 -0.2794)
			(end 0.12065 -0.3048)
			(stroke
				(width 0.1)
				(type default)
			)
			(layer "F.Fab")
		)
		(fp_line
			(start 0.67945 -0.3048)
			(end 0.67945 0.3048)
			(stroke
				(width 0.1)
				(type default)
			)
			(layer "F.Fab")
		)
		(fp_line
			(start 0.67945 0.3048)
			(end 0.120396 0.3048)
			(stroke
				(width 0.1)
				(type default)
			)
			(layer "F.Fab")
		)
		(pad "1" smd circle
			(at -0.40005 0)
			(size 0 0)
			(layers "F.Cu" "F.Mask" "F.Paste")
			(net "PVCCINFAON_CPU0_EN_R")
		)
		(pad "2" smd circle
			(at 0.40005 0)
			(size 0 0)
			(layers "F.Cu" "F.Mask" "F.Paste")
			(net "GND")
		)
	)
	(footprint ""
		(layer "F.Cu")
		(at 19.812 -410.7942 90)
		(property "Reference" "R4729"
			(at 0 0 90)
			(layer "F.SilkS")
			(hide yes)
			(effects
				(font
					(size 1.27 1.27)
				)
			)
		)
		(property "Value" ""
			(at 0 0 90)
			(layer "F.Fab")
			(effects
				(font
					(size 1.27 1.27)
				)
			)
		)
		(duplicate_pad_numbers_are_jumpers no)
		(fp_line
			(start 0.7874 -0.4064)
			(end 0.7874 0.4064)
			(stroke
				(width 0.1524)
				(type default)
			)
			(layer "F.SilkS")
		)
		(fp_line
			(start -0.7874 -0.4064)
			(end 0.7874 -0.4064)
			(stroke
				(width 0.1524)
				(type default)
			)
			(layer "F.SilkS")
		)
		(fp_line
			(start 0.7874 0.4064)
			(end -0.7874 0.4064)
			(stroke
				(width 0.1524)
				(type default)
			)
			(layer "F.SilkS")
		)
		(fp_line
			(start -0.7874 0.4064)
			(end -0.7874 -0.4064)
			(stroke
				(width 0.1524)
				(type default)
			)
			(layer "F.SilkS")
		)
		(fp_line
			(start -0.12065 -0.305054)
			(end -0.12065 -0.2794)
			(stroke
				(width 0.1)
				(type default)
			)
			(layer "F.Fab")
		)
		(fp_line
			(start -0.67945 -0.305054)
			(end -0.12065 -0.305054)
			(stroke
				(width 0.1)
				(type default)
			)
			(layer "F.Fab")
		)
		(fp_line
			(start 0.67945 -0.3048)
			(end 0.67945 0.3048)
			(stroke
				(width 0.1)
				(type default)
			)
			(layer "F.Fab")
		)
		(fp_line
			(start 0.12065 -0.3048)
			(end 0.67945 -0.3048)
			(stroke
				(width 0.1)
				(type default)
			)
			(layer "F.Fab")
		)
		(fp_line
			(start 0.12065 -0.2794)
			(end 0.12065 -0.3048)
			(stroke
				(width 0.1)
				(type default)
			)
			(layer "F.Fab")
		)
		(fp_line
			(start -0.12065 -0.2794)
			(end 0.12065 -0.2794)
			(stroke
				(width 0.1)
				(type default)
			)
			(layer "F.Fab")
		)
		(fp_line
			(start 0.120396 0.2794)
			(end -0.12065 0.2794)
			(stroke
				(width 0.1)
				(type default)
			)
			(layer "F.Fab")
		)
		(fp_line
			(start -0.12065 0.2794)
			(end -0.12065 0.3048)
			(stroke
				(width 0.1)
				(type default)
			)
			(layer "F.Fab")
		)
		(fp_line
			(start 0.67945 0.3048)
			(end 0.120396 0.3048)
			(stroke
				(width 0.1)
				(type default)
			)
			(layer "F.Fab")
		)
		(fp_line
			(start 0.120396 0.3048)
			(end 0.120396 0.2794)
			(stroke
				(width 0.1)
				(type default)
			)
			(layer "F.Fab")
		)
		(fp_line
			(start -0.12065 0.3048)
			(end -0.67945 0.3048)
			(stroke
				(width 0.1)
				(type default)
			)
			(layer "F.Fab")
		)
		(fp_line
			(start -0.67945 0.3048)
			(end -0.67945 -0.305054)
			(stroke
				(width 0.1)
				(type default)
			)
			(layer "F.Fab")
		)
		(pad "1" smd circle
			(at -0.40005 0 90)
			(size 0 0)
			(layers "F.Cu" "F.Mask" "F.Paste")
			(net "GPU_PRSNT_N_ISO")
		)
		(pad "2" smd circle
			(at 0.40005 0 90)
			(size 0 0)
			(layers "F.Cu" "F.Mask" "F.Paste")
			(net "GPU_PRSNT_N_ISO_R1")
		)
	)
)
